(kicad_pcb
	(version 20241229)
	(generator "pcbnew")
	(generator_version "9.0")
	(general
		(thickness 1.62)
		(legacy_teardrops no)
	)
	(paper "A3")
	(title_block
		(title "COM Express 7 Baseboard")
		(date "2025-02-04")
		(rev "1.1.2")
		(company "Antmicro Ltd")
		(comment 1 "www.antmicro.com")
		(comment 9 "footprints 606-610 of 802")
	)
	(layers
		(0 "F.Cu" signal)
		(4 "In1.Cu" signal)
		(6 "In2.Cu" signal)
		(8 "In3.Cu" signal)
		(10 "In4.Cu" signal)
		(12 "In5.Cu" signal)
		(14 "In6.Cu" signal)
		(2 "B.Cu" signal)
		(9 "F.Adhes" user "F.Adhesive")
		(11 "B.Adhes" user "B.Adhesive")
		(13 "F.Paste" user)
		(15 "B.Paste" user)
		(5 "F.SilkS" user "F.Silkscreen")
		(7 "B.SilkS" user "B.Silkscreen")
		(1 "F.Mask" user)
		(3 "B.Mask" user)
		(17 "Dwgs.User" user "User.Drawings")
		(19 "Cmts.User" user "User.Comments")
		(21 "Eco1.User" user "User.Eco1")
		(23 "Eco2.User" user "User.Eco2")
		(25 "Edge.Cuts" user)
		(27 "Margin" user)
		(31 "F.CrtYd" user "F.Courtyard")
		(29 "B.CrtYd" user "B.Courtyard")
		(35 "F.Fab" user)
		(33 "B.Fab" user)
	)
	(footprint "antmicro-footprints:R_0402_1005Metric"
		(layer "B.Cu")
		(at 193.246788 140.972629 135)
		(descr "Resistor SMD 0402")
		(tags "resistor SMD 0402")
		(property "Reference" "R223"
			(at -1.04693 0.452587 135)
			(layer "B.SilkS")
			(effects
				(font
					(size 0.7 0.7)
					(thickness 0.15)
				)
				(justify right top mirror)
			)
		)
		(property "Value" "R_1k_0402"
			(at -1.011843 -1.772046 135)
			(layer "B.Fab")
			(effects
				(font
					(size 0.7 0.7)
					(thickness 0.15)
				)
				(justify right top mirror)
			)
		)
		(property "Datasheet" "https://www.bourns.com/docs/product-datasheets/cr.pdf"
			(at 0 0 135)
			(layer "B.Fab")
			(hide yes)
			(effects
				(font
					(size 1.27 1.27)
					(thickness 0.15)
				)
				(justify mirror)
			)
		)
		(property "Author" "Antmicro"
			(at 331.685 54.215 45)
			(layer "B.Fab")
			(hide yes)
			(effects
				(font
					(size 1 1)
					(thickness 0.15)
				)
				(justify mirror)
			)
		)
		(property "License" "Apache-2.0"
			(at 331.685 54.215 45)
			(layer "B.Fab")
			(hide yes)
			(effects
				(font
					(size 1 1)
					(thickness 0.15)
				)
				(justify mirror)
			)
		)
		(property "MPN" "CR0402-FX-1001GLF"
			(at 331.685 54.215 45)
			(layer "B.Fab")
			(hide yes)
			(effects
				(font
					(size 1 1)
					(thickness 0.15)
				)
				(justify mirror)
			)
		)
		(property "Manufacturer" "Bourns"
			(at 331.685 54.215 45)
			(layer "B.Fab")
			(hide yes)
			(effects
				(font
					(size 1 1)
					(thickness 0.15)
				)
				(justify mirror)
			)
		)
		(property "Public" "False"
			(at 331.685 54.215 45)
			(layer "B.Fab")
			(hide yes)
			(effects
				(font
					(size 1 1)
					(thickness 0.15)
				)
				(justify mirror)
			)
		)
		(property "Tolerance" "1%"
			(at 331.685 54.215 45)
			(layer "B.Fab")
			(hide yes)
			(effects
				(font
					(size 1 1)
					(thickness 0.15)
				)
				(justify mirror)
			)
		)
		(property "Val" "1k"
			(at 331.685 54.215 45)
			(layer "B.Fab")
			(hide yes)
			(effects
				(font
					(size 1 1)
					(thickness 0.15)
				)
				(justify mirror)
			)
		)
		(sheetname "PCIe redriver")
		(sheetfile "pcie_redriver.kicad_sch")
		(attr smd dnp)
		(fp_poly
			(pts
				(xy -0.925 0.47) (xy 0.925 0.47) (xy 0.925 -0.47) (xy -0.925 -0.47)
			)
			(stroke
				(width 0.05)
				(type default)
			)
			(fill no)
			(layer "B.CrtYd")
		)
		(fp_poly
			(pts
				(xy -0.5 0.25) (xy 0.5 0.25) (xy 0.5 -0.25) (xy -0.5 -0.25)
			)
			(stroke
				(width 0.15)
				(type solid)
			)
			(fill no)
			(layer "B.Fab")
		)
		(pad "1" smd roundrect
			(at -0.48 0 135)
			(size 0.59 0.64)
			(layers "B.Cu" "B.Mask" "B.Paste")
			(roundrect_rratio 0.25)
			(net 2 "+3V3")
			(pintype "passive")
			(teardrops
				(best_length_ratio 0.2)
				(max_length 1)
				(best_width_ratio 0.9)
				(max_width 2)
				(curved_edges yes)
				(filter_ratio 0.9)
				(enabled yes)
				(allow_two_segments yes)
				(prefer_zone_connections yes)
			)
		)
		(pad "2" smd roundrect
			(at 0.48 0 135)
			(size 0.59 0.64)
			(layers "B.Cu" "B.Mask" "B.Paste")
			(roundrect_rratio 0.25)
			(net 975 "/PCIe redriver/RX_FG0")
			(pintype "passive")
			(teardrops
				(best_length_ratio 0.2)
				(max_length 1)
				(best_width_ratio 0.9)
				(max_width 2)
				(curved_edges yes)
				(filter_ratio 0.9)
				(enabled yes)
				(allow_two_segments yes)
				(prefer_zone_connections yes)
			)
		)
	)
	(footprint "antmicro-footprints:C_0402_1005Metric"
		(layer "B.Cu")
		(at 120.5 73.61 90)
		(descr "Capacitor SMD 0402")
		(tags "capacitor SMD 0402")
		(property "Reference" "C34"
			(at -1.1 -0.45 90)
			(layer "B.SilkS")
			(effects
				(font
					(size 0.7 0.7)
					(thickness 0.15)
				)
				(justify right bottom mirror)
			)
		)
		(property "Value" "C_100n_0402"
			(at -1.022927 -2.155213 90)
			(layer "B.Fab")
			(effects
				(font
					(size 0.7 0.7)
					(thickness 0.15)
				)
				(justify right bottom mirror)
			)
		)
		(property "Datasheet" "https://www.murata.com/products/productdetail?partno=GRM155R61H104KE14%23"
			(at 0 0 90)
			(layer "F.Fab")
			(hide yes)
			(effects
				(font
					(size 1.27 1.27)
					(thickness 0.15)
				)
			)
		)
		(property "Author" "Antmicro"
			(at 194.11 -46.89 0)
			(layer "B.Fab")
			(hide yes)
			(effects
				(font
					(size 1 1)
					(thickness 0.15)
				)
				(justify mirror)
			)
		)
		(property "Dielectric" "X5R"
			(at 194.11 -46.89 0)
			(layer "B.Fab")
			(hide yes)
			(effects
				(font
					(size 1 1)
					(thickness 0.15)
				)
				(justify mirror)
			)
		)
		(property "License" "Apache-2.0"
			(at 194.11 -46.89 0)
			(layer "B.Fab")
			(hide yes)
			(effects
				(font
					(size 1 1)
					(thickness 0.15)
				)
				(justify mirror)
			)
		)
		(property "MPN" "GRM155R61H104KE14D"
			(at 194.11 -46.89 0)
			(layer "B.Fab")
			(hide yes)
			(effects
				(font
					(size 1 1)
					(thickness 0.15)
				)
				(justify mirror)
			)
		)
		(property "Manufacturer" "Murata"
			(at 194.11 -46.89 0)
			(layer "B.Fab")
			(hide yes)
			(effects
				(font
					(size 1 1)
					(thickness 0.15)
				)
				(justify mirror)
			)
		)
		(property "Public" "False"
			(at 194.11 -46.89 0)
			(layer "B.Fab")
			(hide yes)
			(effects
				(font
					(size 1 1)
					(thickness 0.15)
				)
				(justify mirror)
			)
		)
		(property "Val" "100n"
			(at 194.11 -46.89 0)
			(layer "B.Fab")
			(hide yes)
			(effects
				(font
					(size 1 1)
					(thickness 0.15)
				)
				(justify mirror)
			)
		)
		(property "Voltage" "50V"
			(at 194.11 -46.89 0)
			(layer "B.Fab")
			(hide yes)
			(effects
				(font
					(size 1 1)
					(thickness 0.15)
				)
				(justify mirror)
			)
		)
		(sheetname "USB-C console")
		(sheetfile "usb-c_console.kicad_sch")
		(attr smd)
		(fp_rect
			(start -0.925 0.47)
			(end 0.925 -0.47)
			(stroke
				(width 0.05)
				(type default)
			)
			(fill no)
			(layer "B.CrtYd")
		)
		(fp_line
			(start 0.504 -0.248)
			(end 0.504 0.25)
			(stroke
				(width 0.15)
				(type solid)
			)
			(layer "B.Fab")
		)
		(fp_line
			(start -0.494 -0.248)
			(end 0.504 -0.248)
			(stroke
				(width 0.15)
				(type solid)
			)
			(layer "B.Fab")
		)
		(fp_line
			(start 0.504 0.25)
			(end -0.494 0.25)
			(stroke
				(width 0.15)
				(type solid)
			)
			(layer "B.Fab")
		)
		(fp_line
			(start -0.494 0.25)
			(end -0.494 -0.248)
			(stroke
				(width 0.15)
				(type solid)
			)
			(layer "B.Fab")
		)
		(pad "1" smd roundrect
			(at -0.48 0 90)
			(size 0.59 0.64)
			(layers "B.Cu" "B.Mask" "B.Paste")
			(roundrect_rratio 0.25)
			(net 1 "GND")
			(pintype "passive")
			(teardrops
				(best_length_ratio 0.2)
				(max_length 1)
				(best_width_ratio 0.9)
				(max_width 2)
				(curved_edges yes)
				(filter_ratio 0.9)
				(enabled yes)
				(allow_two_segments yes)
				(prefer_zone_connections yes)
			)
		)
		(pad "2" smd roundrect
			(at 0.48 0 90)
			(size 0.59 0.64)
			(layers "B.Cu" "B.Mask" "B.Paste")
			(roundrect_rratio 0.25)
			(net 58 "/USB-C console/VBUS_FTDI")
			(pintype "passive")
			(teardrops
				(best_length_ratio 0.2)
				(max_length 1)
				(best_width_ratio 0.9)
				(max_width 2)
				(curved_edges yes)
				(filter_ratio 0.9)
				(enabled yes)
				(allow_two_segments yes)
				(prefer_zone_connections yes)
			)
		)
	)
	(footprint "antmicro-footprints:C_0603_1608Metric"
		(layer "B.Cu")
		(at 150.45 162.46 90)
		(descr "Capacitor SMD 0603")
		(tags "capacitor 0603")
		(property "Reference" "C22"
			(at -3.3 0.4 90)
			(layer "B.SilkS")
			(effects
				(font
					(size 0.7 0.7)
					(thickness 0.15)
				)
				(justify right bottom mirror)
			)
		)
		(property "Value" "C_22u_16V_0603"
			(at -1.42757 -1.770288 90)
			(layer "B.Fab")
			(effects
				(font
					(size 0.7 0.7)
					(thickness 0.15)
				)
				(justify right bottom mirror)
			)
		)
		(property "Datasheet" "https://product.samsungsem.com/mlcc/CL10A226MO7JZN.do"
			(at 0 0 90)
			(layer "F.Fab")
			(hide yes)
			(effects
				(font
					(size 1.27 1.27)
					(thickness 0.15)
				)
			)
		)
		(property "Author" "Antmicro"
			(at 312.91 12.01 0)
			(layer "B.Fab")
			(hide yes)
			(effects
				(font
					(size 1 1)
					(thickness 0.15)
				)
				(justify mirror)
			)
		)
		(property "Dielectric" ""
			(at 312.91 12.01 0)
			(layer "B.Fab")
			(hide yes)
			(effects
				(font
					(size 1 1)
					(thickness 0.15)
				)
				(justify mirror)
			)
		)
		(property "License" "Apache-2.0"
			(at 312.91 12.01 0)
			(layer "B.Fab")
			(hide yes)
			(effects
				(font
					(size 1 1)
					(thickness 0.15)
				)
				(justify mirror)
			)
		)
		(property "MPN" "CL10A226MO7JZNC"
			(at 312.91 12.01 0)
			(layer "B.Fab")
			(hide yes)
			(effects
				(font
					(size 1 1)
					(thickness 0.15)
				)
				(justify mirror)
			)
		)
		(property "Manufacturer" "Samsung Electro-Mechanics"
			(at 312.91 12.01 0)
			(layer "B.Fab")
			(hide yes)
			(effects
				(font
					(size 1 1)
					(thickness 0.15)
				)
				(justify mirror)
			)
		)
		(property "Public" "False"
			(at 312.91 12.01 0)
			(layer "B.Fab")
			(hide yes)
			(effects
				(font
					(size 1 1)
					(thickness 0.15)
				)
				(justify mirror)
			)
		)
		(property "Val" "22u"
			(at 312.91 12.01 0)
			(layer "B.Fab")
			(hide yes)
			(effects
				(font
					(size 1 1)
					(thickness 0.15)
				)
				(justify mirror)
			)
		)
		(property "Voltage" "16V"
			(at 312.91 12.01 0)
			(layer "B.Fab")
			(hide yes)
			(effects
				(font
					(size 1 1)
					(thickness 0.15)
				)
				(justify mirror)
			)
		)
		(sheetname "2xSFP+")
		(sheetfile "2xSFP+.kicad_sch")
		(attr smd)
		(fp_line
			(start 0.15 -0.4)
			(end -0.15 -0.4)
			(stroke
				(width 0.15)
				(type solid)
			)
			(layer "B.SilkS")
		)
		(fp_line
			(start 0.15 0.4)
			(end -0.15 0.4)
			(stroke
				(width 0.15)
				(type solid)
			)
			(layer "B.SilkS")
		)
		(fp_rect
			(start -1.25 0.65)
			(end 1.25 -0.65)
			(stroke
				(width 0.05)
				(type solid)
			)
			(fill no)
			(layer "B.CrtYd")
		)
		(fp_rect
			(start -0.8 0.4)
			(end 0.8 -0.4)
			(stroke
				(width 0.15)
				(type solid)
			)
			(fill no)
			(layer "B.Fab")
		)
		(pad "1" smd roundrect
			(at -0.7 0 90)
			(size 0.8 1)
			(layers "B.Cu" "B.Mask" "B.Paste")
			(roundrect_rratio 0.2)
			(net 1 "GND")
			(pintype "passive")
			(teardrops
				(best_length_ratio 0.2)
				(max_length 1)
				(best_width_ratio 0.9)
				(max_width 2)
				(curved_edges yes)
				(filter_ratio 0.9)
				(enabled yes)
				(allow_two_segments yes)
				(prefer_zone_connections yes)
			)
		)
		(pad "2" smd roundrect
			(at 0.7 0 90)
			(size 0.8 1)
			(layers "B.Cu" "B.Mask" "B.Paste")
			(roundrect_rratio 0.2)
			(net 2 "+3V3")
			(pintype "passive")
			(teardrops
				(best_length_ratio 0.2)
				(max_length 1)
				(best_width_ratio 0.9)
				(max_width 2)
				(curved_edges yes)
				(filter_ratio 0.9)
				(enabled yes)
				(allow_two_segments yes)
				(prefer_zone_connections yes)
			)
		)
	)
	(footprint "antmicro-footprints:R_0402_1005Metric"
		(layer "B.Cu")
		(at 192.539682 141.679736 135)
		(descr "Resistor SMD 0402")
		(tags "resistor SMD 0402")
		(property "Reference" "R221"
			(at -1.04693 0.452587 135)
			(layer "B.SilkS")
			(effects
				(font
					(size 0.7 0.7)
					(thickness 0.15)
				)
				(justify right top mirror)
			)
		)
		(property "Value" "R_1k_0402"
			(at -1.011843 -1.772046 135)
			(layer "B.Fab")
			(effects
				(font
					(size 0.7 0.7)
					(thickness 0.15)
				)
				(justify right top mirror)
			)
		)
		(property "Datasheet" "https://www.bourns.com/docs/product-datasheets/cr.pdf"
			(at 0 0 135)
			(layer "B.Fab")
			(hide yes)
			(effects
				(font
					(size 1.27 1.27)
					(thickness 0.15)
				)
				(justify mirror)
			)
		)
		(property "Author" "Antmicro"
			(at 332.685 55.214999 45)
			(layer "B.Fab")
			(hide yes)
			(effects
				(font
					(size 1 1)
					(thickness 0.15)
				)
				(justify mirror)
			)
		)
		(property "License" "Apache-2.0"
			(at 332.685 55.214999 45)
			(layer "B.Fab")
			(hide yes)
			(effects
				(font
					(size 1 1)
					(thickness 0.15)
				)
				(justify mirror)
			)
		)
		(property "MPN" "CR0402-FX-1001GLF"
			(at 332.685 55.214999 45)
			(layer "B.Fab")
			(hide yes)
			(effects
				(font
					(size 1 1)
					(thickness 0.15)
				)
				(justify mirror)
			)
		)
		(property "Manufacturer" "Bourns"
			(at 332.685 55.214999 45)
			(layer "B.Fab")
			(hide yes)
			(effects
				(font
					(size 1 1)
					(thickness 0.15)
				)
				(justify mirror)
			)
		)
		(property "Public" "False"
			(at 332.685 55.214999 45)
			(layer "B.Fab")
			(hide yes)
			(effects
				(font
					(size 1 1)
					(thickness 0.15)
				)
				(justify mirror)
			)
		)
		(property "Tolerance" "1%"
			(at 332.685 55.214999 45)
			(layer "B.Fab")
			(hide yes)
			(effects
				(font
					(size 1 1)
					(thickness 0.15)
				)
				(justify mirror)
			)
		)
		(property "Val" "1k"
			(at 332.685 55.214999 45)
			(layer "B.Fab")
			(hide yes)
			(effects
				(font
					(size 1 1)
					(thickness 0.15)
				)
				(justify mirror)
			)
		)
		(sheetname "PCIe redriver")
		(sheetfile "pcie_redriver.kicad_sch")
		(attr smd)
		(fp_poly
			(pts
				(xy -0.925 0.47) (xy 0.925 0.47) (xy 0.925 -0.47) (xy -0.925 -0.47)
			)
			(stroke
				(width 0.05)
				(type default)
			)
			(fill no)
			(layer "B.CrtYd")
		)
		(fp_poly
			(pts
				(xy -0.5 0.25) (xy 0.5 0.25) (xy 0.5 -0.25) (xy -0.5 -0.25)
			)
			(stroke
				(width 0.15)
				(type solid)
			)
			(fill no)
			(layer "B.Fab")
		)
		(pad "1" smd roundrect
			(at -0.48 0 135)
			(size 0.59 0.64)
			(layers "B.Cu" "B.Mask" "B.Paste")
			(roundrect_rratio 0.25)
			(net 2 "+3V3")
			(pintype "passive")
			(teardrops
				(best_length_ratio 0.2)
				(max_length 1)
				(best_width_ratio 0.9)
				(max_width 2)
				(curved_edges yes)
				(filter_ratio 0.9)
				(enabled yes)
				(allow_two_segments yes)
				(prefer_zone_connections yes)
			)
		)
		(pad "2" smd roundrect
			(at 0.48 0 135)
			(size 0.59 0.64)
			(layers "B.Cu" "B.Mask" "B.Paste")
			(roundrect_rratio 0.25)
			(net 974 "/PCIe redriver/RX_FG1")
			(pintype "passive")
			(teardrops
				(best_length_ratio 0.2)
				(max_length 1)
				(best_width_ratio 0.9)
				(max_width 2)
				(curved_edges yes)
				(filter_ratio 0.9)
				(enabled yes)
				(allow_two_segments yes)
				(prefer_zone_connections yes)
			)
		)
	)
	(footprint "antmicro-footprints:R_0402_1005Metric"
		(layer "B.Cu")
		(at 143.05 169.16 -90)
		(descr "Resistor SMD 0402")
		(tags "resistor SMD 0402")
		(property "Reference" "R51"
			(at -3.9 13.5 90)
			(layer "B.SilkS")
			(effects
				(font
					(size 0.7 0.7)
					(thickness 0.15)
				)
				(justify left bottom mirror)
			)
		)
		(property "Value" "R_1k_0402"
			(at -1.011843 -1.772047 90)
			(layer "B.Fab")
			(effects
				(font
					(size 0.7 0.7)
					(thickness 0.15)
				)
				(justify left bottom mirror)
			)
		)
		(property "Datasheet" "https://www.bourns.com/docs/product-datasheets/cr.pdf"
			(at 0 0 270)
			(layer "F.Fab")
			(hide yes)
			(effects
				(font
					(size 1.27 1.27)
					(thickness 0.15)
				)
			)
		)
		(property "Author" "Antmicro"
			(at -26.11 312.21 0)
			(layer "B.Fab")
			(hide yes)
			(effects
				(font
					(size 1 1)
					(thickness 0.15)
				)
				(justify mirror)
			)
		)
		(property "License" "Apache-2.0"
			(at -26.11 312.21 0)
			(layer "B.Fab")
			(hide yes)
			(effects
				(font
					(size 1 1)
					(thickness 0.15)
				)
				(justify mirror)
			)
		)
		(property "MPN" "CR0402-FX-1001GLF"
			(at -26.11 312.21 0)
			(layer "B.Fab")
			(hide yes)
			(effects
				(font
					(size 1 1)
					(thickness 0.15)
				)
				(justify mirror)
			)
		)
		(property "Manufacturer" "Bourns"
			(at -26.11 312.21 0)
			(layer "B.Fab")
			(hide yes)
			(effects
				(font
					(size 1 1)
					(thickness 0.15)
				)
				(justify mirror)
			)
		)
		(property "Public" "False"
			(at -26.11 312.21 0)
			(layer "B.Fab")
			(hide yes)
			(effects
				(font
					(size 1 1)
					(thickness 0.15)
				)
				(justify mirror)
			)
		)
		(property "Tolerance" "1%"
			(at -26.11 312.21 0)
			(layer "B.Fab")
			(hide yes)
			(effects
				(font
					(size 1 1)
					(thickness 0.15)
				)
				(justify mirror)
			)
		)
		(property "Val" "1k"
			(at -26.11 312.21 0)
			(layer "B.Fab")
			(hide yes)
			(effects
				(font
					(size 1 1)
					(thickness 0.15)
				)
				(justify mirror)
			)
		)
		(sheetname "2xSFP+")
		(sheetfile "2xSFP+.kicad_sch")
		(attr smd)
		(fp_rect
			(start -0.925 0.47)
			(end 0.925 -0.47)
			(stroke
				(width 0.05)
				(type default)
			)
			(fill no)
			(layer "B.CrtYd")
		)
		(fp_rect
			(start -0.5 0.25)
			(end 0.5 -0.25)
			(stroke
				(width 0.15)
				(type solid)
			)
			(fill no)
			(layer "B.Fab")
		)
		(pad "1" smd roundrect
			(at -0.48 0 270)
			(size 0.59 0.64)
			(layers "B.Cu" "B.Mask" "B.Paste")
			(roundrect_rratio 0.25)
			(net 162 "Net-(J2A-TX_{FAULT})")
			(pintype "passive")
			(teardrops
				(best_length_ratio 0.2)
				(max_length 1)
				(best_width_ratio 0.9)
				(max_width 2)
				(curved_edges yes)
				(filter_ratio 0.9)
				(enabled yes)
				(allow_two_segments yes)
				(prefer_zone_connections yes)
			)
		)
		(pad "2" smd roundrect
			(at 0.48 0 270)
			(size 0.59 0.64)
			(layers "B.Cu" "B.Mask" "B.Paste")
			(roundrect_rratio 0.25)
			(net 2 "+3V3")
			(pintype "passive")
			(teardrops
				(best_length_ratio 0.2)
				(max_length 1)
				(best_width_ratio 0.9)
				(max_width 2)
				(curved_edges yes)
				(filter_ratio 0.9)
				(enabled yes)
				(allow_two_segments yes)
				(prefer_zone_connections yes)
			)
		)
	)
)
